(kicad_pcb
	(version 20260206)
	(generator "pcbnew")
	(generator_version "10.0")
	(general
		(thickness 1.6)
		(legacy_teardrops no)
	)
	(paper "A4")
	(title_block
		(title "03242023_DA0F0TMBIJ0_F0T_Motherboard_J_brd_V01_OCP.brd")
		(comment 1 "Grand Teton / footprint 1682 of 6105 (U1), pads 211-318 of 4677")
	)
	(layers
		(0 "F.Cu" signal "TOP")
		(4 "In1.Cu" signal "GND")
		(6 "In2.Cu" signal "IN1")
		(8 "In3.Cu" signal "GND1")
		(10 "In4.Cu" signal "IN2")
		(12 "In5.Cu" signal "GND2")
		(14 "In6.Cu" signal "IN3")
		(16 "In7.Cu" signal "GND3")
		(18 "In8.Cu" signal "VCC")
		(20 "In9.Cu" signal "VCC1")
		(22 "In10.Cu" signal "GND4")
		(24 "In11.Cu" signal "IN4")
		(26 "In12.Cu" signal "GND5")
		(28 "In13.Cu" signal "IN5")
		(30 "In14.Cu" signal "GND6")
		(32 "In15.Cu" signal "IN6")
		(34 "In16.Cu" signal "GND7")
		(2 "B.Cu" signal "BOTTOM")
		(9 "F.Adhes" user "F.Adhesive")
		(11 "B.Adhes" user "B.Adhesive")
		(13 "F.Paste" user "Package Geometry/Pastemask Top")
		(15 "B.Paste" user "Package Geometry/Pastemask Bottom")
		(5 "F.SilkS" user "Ref Des/Silkscreen Top")
		(7 "B.SilkS" user "Ref Des/Silkscreen Bottom")
		(1 "F.Mask" user "Board Geometry/Soldermask Top")
		(3 "B.Mask" user "Board Geometry/Soldermask Bottom")
		(17 "Dwgs.User" user "User.Drawings")
		(19 "Cmts.User" user "User.Comments")
		(21 "Eco1.User" user "User.Eco1")
		(23 "Eco2.User" user "User.Eco2")
		(25 "Edge.Cuts" user "Board Geometry/Outline")
		(27 "Margin" user)
		(31 "F.CrtYd" user "Package Geometry/Place Bound Top")
		(29 "B.CrtYd" user "Package Geometry/Place Bound Bottom")
		(35 "F.Fab" user "Ref Des/Assembly Top")
		(33 "B.Fab" user "Ref Des/Assembly Bottom")
	)
	(footprint ""
		(layer "F.Cu")
		(at 111.93018 -251.76988 90)
		(property "Reference" "U1"
			(at -74.913236 41.548812 0)
			(unlocked yes)
			(layer "F.SilkS")
			(effects
				(font
					(size 1.6002 1.1938)
					(thickness 0.1524)
				)
				(justify left)
			)
		)
		(property "Value" ""
			(at 0 0 90)
			(layer "F.Fab")
			(effects
				(font
					(size 1.27 1.27)
				)
			)
		)
		(duplicate_pad_numbers_are_jumpers no)
		(pad "AE9" smd circle
			(at -30.914086 -15.796514 270)
			(size 0.4318 0.4318)
			(layers "F.Cu" "F.Mask" "F.Paste")
			(net "P5E_CPU1_PE0_RX_DN<7>")
		)
		(pad "AE11" smd circle
			(at -29.2862 -15.796514 270)
			(size 0.4318 0.4318)
			(layers "F.Cu" "F.Mask" "F.Paste")
			(net "PVCCFA_EHV_FIVRA_CPU1")
		)
		(pad "AE13" smd circle
			(at -27.658314 -15.796514 270)
			(size 0.4318 0.4318)
			(layers "F.Cu" "F.Mask" "F.Paste")
			(net "P5E_CPU1_PE0_TX_DN<6>")
		)
		(pad "AE15" smd circle
			(at -26.030682 -15.796514 270)
			(size 0.4318 0.4318)
			(layers "F.Cu" "F.Mask" "F.Paste")
			(net "PVCCFA_EHV_FIVRA_CPU1")
		)
		(pad "AE17" smd circle
			(at -24.402796 -15.796514 270)
			(size 0.4318 0.4318)
			(layers "F.Cu" "F.Mask" "F.Paste")
			(net "GND")
		)
		(pad "AE19" smd circle
			(at -22.77491 -15.796514 270)
			(size 0.4318 0.4318)
			(layers "F.Cu" "F.Mask" "F.Paste")
			(net "GND")
		)
		(pad "AE21" smd circle
			(at -21.147278 -15.796514 270)
			(size 0.4318 0.4318)
			(layers "F.Cu" "F.Mask" "F.Paste")
			(net "GND")
		)
		(pad "AE23" smd circle
			(at -19.519392 -15.796514 270)
			(size 0.4318 0.4318)
			(layers "F.Cu" "F.Mask" "F.Paste")
			(net "GND")
		)
		(pad "AE25" smd circle
			(at -17.89176 -15.796514 270)
			(size 0.4318 0.4318)
			(layers "F.Cu" "F.Mask" "F.Paste")
			(net "GND")
		)
		(pad "AE27" smd circle
			(at -16.263874 -15.796514 270)
			(size 0.4318 0.4318)
			(layers "F.Cu" "F.Mask" "F.Paste")
			(net "GND")
		)
		(pad "AE29" smd circle
			(at -14.635988 -15.796514 270)
			(size 0.4318 0.4318)
			(layers "F.Cu" "F.Mask" "F.Paste")
			(net "GND")
		)
		(pad "AE31" smd circle
			(at -13.008356 -15.796514 270)
			(size 0.4318 0.4318)
			(layers "F.Cu" "F.Mask" "F.Paste")
			(net "GND")
		)
		(pad "AE33" smd circle
			(at -11.380724 -15.796514 270)
			(size 0.4318 0.4318)
			(layers "F.Cu" "F.Mask" "F.Paste")
			(net "GND")
		)
		(pad "AE35" smd circle
			(at -9.752838 -15.796514 270)
			(size 0.4318 0.4318)
			(layers "F.Cu" "F.Mask" "F.Paste")
			(net "GND")
		)
		(pad "AE37" smd circle
			(at -8.124952 -15.796514 270)
			(size 0.4318 0.4318)
			(layers "F.Cu" "F.Mask" "F.Paste")
			(net "GND")
		)
		(pad "AE39" smd circle
			(at -6.49732 -15.796514 270)
			(size 0.4318 0.4318)
			(layers "F.Cu" "F.Mask" "F.Paste")
			(net "GND")
		)
		(pad "AE41" smd circle
			(at -4.869434 -15.796514 270)
			(size 0.4318 0.4318)
			(layers "F.Cu" "F.Mask" "F.Paste")
			(net "GND")
		)
		(pad "AE43" smd circle
			(at -3.241802 -15.796514 270)
			(size 0.4318 0.4318)
			(layers "F.Cu" "F.Mask" "F.Paste")
			(net "GND")
		)
		(pad "AE45" smd circle
			(at -1.613916 -15.796514 270)
			(size 0.4318 0.4318)
			(layers "F.Cu" "F.Mask" "F.Paste")
			(net "GND")
		)
		(pad "AE48" smd circle
			(at 2.427732 -15.686532 270)
			(size 0.4318 0.4318)
			(layers "F.Cu" "F.Mask" "F.Paste")
			(net "GND")
		)
		(pad "AE50" smd circle
			(at 4.055618 -15.686532 270)
			(size 0.4318 0.4318)
			(layers "F.Cu" "F.Mask" "F.Paste")
			(net "GND")
		)
		(pad "AE52" smd circle
			(at 5.68325 -15.686532 270)
			(size 0.4318 0.4318)
			(layers "F.Cu" "F.Mask" "F.Paste")
			(net "GND")
		)
		(pad "AE54" smd circle
			(at 7.311136 -15.686532 270)
			(size 0.4318 0.4318)
			(layers "F.Cu" "F.Mask" "F.Paste")
			(net "GND")
		)
		(pad "AE56" smd circle
			(at 8.939022 -15.686532 270)
			(size 0.4318 0.4318)
			(layers "F.Cu" "F.Mask" "F.Paste")
			(net "GND")
		)
		(pad "AE58" smd circle
			(at 10.566654 -15.686532 270)
			(size 0.4318 0.4318)
			(layers "F.Cu" "F.Mask" "F.Paste")
			(net "GND")
		)
		(pad "AE60" smd circle
			(at 12.19454 -15.686532 270)
			(size 0.4318 0.4318)
			(layers "F.Cu" "F.Mask" "F.Paste")
			(net "GND")
		)
		(pad "AE62" smd circle
			(at 13.822426 -15.686532 270)
			(size 0.4318 0.4318)
			(layers "F.Cu" "F.Mask" "F.Paste")
			(net "GND")
		)
		(pad "AE64" smd circle
			(at 15.450058 -15.686532 270)
			(size 0.4318 0.4318)
			(layers "F.Cu" "F.Mask" "F.Paste")
			(net "GND")
		)
		(pad "AE66" smd circle
			(at 17.07769 -15.686532 270)
			(size 0.4318 0.4318)
			(layers "F.Cu" "F.Mask" "F.Paste")
			(net "GND")
		)
		(pad "AE68" smd circle
			(at 18.705576 -15.686532 270)
			(size 0.4318 0.4318)
			(layers "F.Cu" "F.Mask" "F.Paste")
			(net "GND")
		)
		(pad "AE70" smd circle
			(at 20.333462 -15.686532 270)
			(size 0.4318 0.4318)
			(layers "F.Cu" "F.Mask" "F.Paste")
			(net "GND")
		)
		(pad "AE72" smd circle
			(at 21.961094 -15.686532 270)
			(size 0.4318 0.4318)
			(layers "F.Cu" "F.Mask" "F.Paste")
			(net "GND")
		)
		(pad "AE74" smd circle
			(at 23.58898 -15.686532 270)
			(size 0.4318 0.4318)
			(layers "F.Cu" "F.Mask" "F.Paste")
			(net "GND")
		)
		(pad "AE76" smd circle
			(at 25.216612 -15.686532 270)
			(size 0.4318 0.4318)
			(layers "F.Cu" "F.Mask" "F.Paste")
			(net "GND")
		)
		(pad "AE78" smd circle
			(at 26.844498 -15.686532 270)
			(size 0.4318 0.4318)
			(layers "F.Cu" "F.Mask" "F.Paste")
			(net "GND")
		)
		(pad "AE80" smd circle
			(at 28.472384 -15.686532 270)
			(size 0.4318 0.4318)
			(layers "F.Cu" "F.Mask" "F.Paste")
			(net "UPI_CPU0_CPU1_P2P2_DP<6>")
		)
		(pad "AE82" smd circle
			(at 30.100016 -15.686532 270)
			(size 0.4318 0.4318)
			(layers "F.Cu" "F.Mask" "F.Paste")
			(net "UPI_CPU0_CPU1_P2P2_DN<9>")
		)
		(pad "AE84" smd circle
			(at 31.727902 -15.686532 270)
			(size 0.4318 0.4318)
			(layers "F.Cu" "F.Mask" "F.Paste")
			(net "GND")
		)
		(pad "AE86" smd circle
			(at 33.355534 -15.686532 270)
			(size 0.4318 0.4318)
			(layers "F.Cu" "F.Mask" "F.Paste")
			(net "P5E_CPU1_PE4_TX_DN<7>")
		)
		(pad "AE88" smd circle
			(at 34.98342 -15.686532 270)
			(size 0.4318 0.4318)
			(layers "F.Cu" "F.Mask" "F.Paste")
			(net "GND")
		)
		(pad "AE90" smd circle
			(at 36.611306 -15.686532 270)
			(size 0.4318 0.4318)
			(layers "F.Cu" "F.Mask" "F.Paste")
			(net "P5E_CPU1_PE4_RX_DP<7>")
		)
		(pad "AF2" smd circle
			(at -36.611306 -15.326868 270)
			(size 0.4318 0.4318)
			(layers "F.Cu" "F.Mask" "F.Paste")
			(net "UPI_CPU1_CPU0_P0P1_DN<8>")
		)
		(pad "AF4" smd circle
			(at -34.98342 -15.326868 270)
			(size 0.4318 0.4318)
			(layers "F.Cu" "F.Mask" "F.Paste")
			(net "GND")
		)
		(pad "AF6" smd circle
			(at -33.355534 -15.326868 270)
			(size 0.4318 0.4318)
			(layers "F.Cu" "F.Mask" "F.Paste")
			(net "UPI_CPU0_CPU1_P1P0_DN<8>")
		)
		(pad "AF8" smd circle
			(at -31.727902 -15.326868 270)
			(size 0.4318 0.4318)
			(layers "F.Cu" "F.Mask" "F.Paste")
			(net "GND")
		)
		(pad "AF10" smd circle
			(at -30.100016 -15.326868 270)
			(size 0.4318 0.4318)
			(layers "F.Cu" "F.Mask" "F.Paste")
			(net "P5E_CPU1_PE0_RX_DN<8>")
		)
		(pad "AF12" smd circle
			(at -28.472384 -15.326868 270)
			(size 0.4318 0.4318)
			(layers "F.Cu" "F.Mask" "F.Paste")
			(net "GND")
		)
		(pad "AF14" smd circle
			(at -26.844498 -15.326868 270)
			(size 0.4318 0.4318)
			(layers "F.Cu" "F.Mask" "F.Paste")
			(net "P5E_CPU1_PE0_TX_DN<7>")
		)
		(pad "AF16" smd circle
			(at -25.216612 -15.326868 270)
			(size 0.4318 0.4318)
			(layers "F.Cu" "F.Mask" "F.Paste")
			(net "GND")
		)
		(pad "AF18" smd circle
			(at -23.58898 -15.326868 270)
			(size 0.4318 0.4318)
			(layers "F.Cu" "F.Mask" "F.Paste")
			(net "M_C_CPU1_SB_DQS_DN<8>")
		)
		(pad "AF20" smd circle
			(at -21.961094 -15.326868 270)
			(size 0.4318 0.4318)
			(layers "F.Cu" "F.Mask" "F.Paste")
			(net "M_C_CPU1_SB_DQ<26>")
		)
		(pad "AF22" smd circle
			(at -20.333462 -15.326868 270)
			(size 0.4318 0.4318)
			(layers "F.Cu" "F.Mask" "F.Paste")
			(net "M_D_CPU1_SB_DQ<23>")
		)
		(pad "AF24" smd circle
			(at -18.705576 -15.326868 270)
			(size 0.4318 0.4318)
			(layers "F.Cu" "F.Mask" "F.Paste")
			(net "M_D_CPU1_SB_DQS_DN<7>")
		)
		(pad "AF26" smd circle
			(at -17.07769 -15.326868 270)
			(size 0.4318 0.4318)
			(layers "F.Cu" "F.Mask" "F.Paste")
			(net "M_D_CPU1_SB_DQ<18>")
		)
		(pad "AF28" smd circle
			(at -15.450058 -15.326868 270)
			(size 0.4318 0.4318)
			(layers "F.Cu" "F.Mask" "F.Paste")
			(net "M_C_CPU1_SB_DQ<15>")
		)
		(pad "AF30" smd circle
			(at -13.822426 -15.326868 270)
			(size 0.4318 0.4318)
			(layers "F.Cu" "F.Mask" "F.Paste")
			(net "M_C_CPU1_SB_DQS_DN<6>")
		)
		(pad "AF32" smd circle
			(at -12.19454 -15.326868 270)
			(size 0.4318 0.4318)
			(layers "F.Cu" "F.Mask" "F.Paste")
			(net "M_C_CPU1_SB_DQ<10>")
		)
		(pad "AF34" smd circle
			(at -10.566654 -15.326868 270)
			(size 0.4318 0.4318)
			(layers "F.Cu" "F.Mask" "F.Paste")
			(net "M_C_CPU1_SB_DQ<7>")
		)
		(pad "AF36" smd circle
			(at -8.939022 -15.326868 270)
			(size 0.4318 0.4318)
			(layers "F.Cu" "F.Mask" "F.Paste")
			(net "M_C_CPU1_SB_DQS_DN<5>")
		)
		(pad "AF38" smd circle
			(at -7.311136 -15.326868 270)
			(size 0.4318 0.4318)
			(layers "F.Cu" "F.Mask" "F.Paste")
			(net "M_C_CPU1_SB_DQ<2>")
		)
		(pad "AF40" smd circle
			(at -5.68325 -15.326868 270)
			(size 0.4318 0.4318)
			(layers "F.Cu" "F.Mask" "F.Paste")
			(net "M_D_CPU1_SB_CS_N<2>")
		)
		(pad "AF42" smd circle
			(at -4.055618 -15.326868 270)
			(size 0.4318 0.4318)
			(layers "F.Cu" "F.Mask" "F.Paste")
			(net "GND")
		)
		(pad "AF44" smd circle
			(at -2.427732 -15.326868 270)
			(size 0.4318 0.4318)
			(layers "F.Cu" "F.Mask" "F.Paste")
			(net "M_D_CPU1_SB_CA<3>")
		)
		(pad "AF47" smd circle
			(at 1.613916 -15.216886 270)
			(size 0.4318 0.4318)
			(layers "F.Cu" "F.Mask" "F.Paste")
			(net "M_C_CPU1_SB_RSP<1>")
		)
		(pad "AF49" smd circle
			(at 3.241802 -15.216886 270)
			(size 0.4318 0.4318)
			(layers "F.Cu" "F.Mask" "F.Paste")
			(net "M_C_CPU1_CLK_DN<1>")
		)
		(pad "AF51" smd circle
			(at 4.869434 -15.216886 270)
			(size 0.4318 0.4318)
			(layers "F.Cu" "F.Mask" "F.Paste")
			(net "M_D_CPU1_SB_RSP<0>")
		)
		(pad "AF53" smd circle
			(at 6.49732 -15.216886 270)
			(size 0.4318 0.4318)
			(layers "F.Cu" "F.Mask" "F.Paste")
			(net "M_C_CPU1_SA_CB<7>")
		)
		(pad "AF55" smd circle
			(at 8.124952 -15.216886 270)
			(size 0.4318 0.4318)
			(layers "F.Cu" "F.Mask" "F.Paste")
			(net "M_C_CPU1_SA_DQS_DP<9>")
		)
		(pad "AF57" smd circle
			(at 9.752838 -15.216886 270)
			(size 0.4318 0.4318)
			(layers "F.Cu" "F.Mask" "F.Paste")
			(net "M_C_CPU1_SA_CB<2>")
		)
		(pad "AF59" smd circle
			(at 11.380724 -15.216886 270)
			(size 0.4318 0.4318)
			(layers "F.Cu" "F.Mask" "F.Paste")
			(net "M_C_CPU1_SA_DQ<31>")
		)
		(pad "AF61" smd circle
			(at 13.008356 -15.216886 270)
			(size 0.4318 0.4318)
			(layers "F.Cu" "F.Mask" "F.Paste")
			(net "M_C_CPU1_SA_DQS_DN<8>")
		)
		(pad "AF63" smd circle
			(at 14.635988 -15.216886 270)
			(size 0.4318 0.4318)
			(layers "F.Cu" "F.Mask" "F.Paste")
			(net "M_C_CPU1_SA_DQ<26>")
		)
		(pad "AF65" smd circle
			(at 16.263874 -15.216886 270)
			(size 0.4318 0.4318)
			(layers "F.Cu" "F.Mask" "F.Paste")
			(net "M_C_CPU1_SA_DQ<15>")
		)
		(pad "AF67" smd circle
			(at 17.89176 -15.216886 270)
			(size 0.4318 0.4318)
			(layers "F.Cu" "F.Mask" "F.Paste")
			(net "M_C_CPU1_SA_DQS_DP<6>")
		)
		(pad "AF69" smd circle
			(at 19.519392 -15.216886 270)
			(size 0.4318 0.4318)
			(layers "F.Cu" "F.Mask" "F.Paste")
			(net "M_C_CPU1_SA_DQ<10>")
		)
		(pad "AF71" smd circle
			(at 21.147278 -15.216886 270)
			(size 0.4318 0.4318)
			(layers "F.Cu" "F.Mask" "F.Paste")
			(net "M_D_CPU1_SA_DQ<7>")
		)
		(pad "AF73" smd circle
			(at 22.77491 -15.216886 270)
			(size 0.4318 0.4318)
			(layers "F.Cu" "F.Mask" "F.Paste")
			(net "M_D_CPU1_SA_DQS_DP<5>")
		)
		(pad "AF75" smd circle
			(at 24.402796 -15.216886 270)
			(size 0.4318 0.4318)
			(layers "F.Cu" "F.Mask" "F.Paste")
			(net "M_D_CPU1_SA_DQ<2>")
		)
		(pad "AF77" smd circle
			(at 26.030682 -15.216886 270)
			(size 0.4318 0.4318)
			(layers "F.Cu" "F.Mask" "F.Paste")
			(net "PVCCFA_EHV_FIVRA_CPU1")
		)
		(pad "AF79" smd circle
			(at 27.658314 -15.216886 270)
			(size 0.4318 0.4318)
			(layers "F.Cu" "F.Mask" "F.Paste")
			(net "UPI_CPU0_CPU1_P2P2_DN<8>")
		)
		(pad "AF81" smd circle
			(at 29.2862 -15.216886 270)
			(size 0.4318 0.4318)
			(layers "F.Cu" "F.Mask" "F.Paste")
			(net "GND")
		)
		(pad "AF83" smd circle
			(at 30.914086 -15.216886 270)
			(size 0.4318 0.4318)
			(layers "F.Cu" "F.Mask" "F.Paste")
			(net "UPI_CPU0_CPU1_P2P2_DP<9>")
		)
		(pad "AF85" smd circle
			(at 32.541718 -15.216886 270)
			(size 0.4318 0.4318)
			(layers "F.Cu" "F.Mask" "F.Paste")
			(net "P5E_CPU1_PE4_TX_DP<7>")
		)
		(pad "AF87" smd circle
			(at 34.169604 -15.216886 270)
			(size 0.4318 0.4318)
			(layers "F.Cu" "F.Mask" "F.Paste")
			(net "GND")
		)
		(pad "AF89" smd circle
			(at 35.797236 -15.216886 270)
			(size 0.4318 0.4318)
			(layers "F.Cu" "F.Mask" "F.Paste")
			(net "P5E_CPU1_PE4_RX_DN<7>")
		)
		(pad "AF91" smd oval
			(at 37.425122 -15.216886)
			(size 0.381 0.4826)
			(drill
				(offset 0 -0.0508)
			)
			(layers "F.Cu" "F.Mask" "F.Paste")
			(net "GND")
		)
		(pad "AG1" smd oval
			(at -37.425122 -14.856714 180)
			(size 0.381 0.4826)
			(drill
				(offset 0 -0.0508)
			)
			(layers "F.Cu" "F.Mask" "F.Paste")
			(net "GND")
		)
		(pad "AG3" smd circle
			(at -35.797236 -14.856714 270)
			(size 0.4318 0.4318)
			(layers "F.Cu" "F.Mask" "F.Paste")
			(net "UPI_CPU1_CPU0_P0P1_DP<9>")
		)
		(pad "AG5" smd circle
			(at -34.169604 -14.856714 270)
			(size 0.4318 0.4318)
			(layers "F.Cu" "F.Mask" "F.Paste")
			(net "GND")
		)
		(pad "AG7" smd circle
			(at -32.541718 -14.856714 270)
			(size 0.4318 0.4318)
			(layers "F.Cu" "F.Mask" "F.Paste")
			(net "UPI_CPU0_CPU1_P1P0_DP<8>")
		)
		(pad "AG9" smd circle
			(at -30.914086 -14.856714 270)
			(size 0.4318 0.4318)
			(layers "F.Cu" "F.Mask" "F.Paste")
			(net "GND")
		)
		(pad "AG11" smd circle
			(at -29.2862 -14.856714 270)
			(size 0.4318 0.4318)
			(layers "F.Cu" "F.Mask" "F.Paste")
			(net "P5E_CPU1_PE0_RX_DP<8>")
		)
		(pad "AG13" smd circle
			(at -27.658314 -14.856714 270)
			(size 0.4318 0.4318)
			(layers "F.Cu" "F.Mask" "F.Paste")
			(net "GND")
		)
		(pad "AG15" smd circle
			(at -26.030682 -14.856714 270)
			(size 0.4318 0.4318)
			(layers "F.Cu" "F.Mask" "F.Paste")
			(net "P5E_CPU1_PE0_TX_DP<7>")
		)
		(pad "AG17" smd circle
			(at -24.402796 -14.856714 270)
			(size 0.4318 0.4318)
			(layers "F.Cu" "F.Mask" "F.Paste")
			(net "M_C_CPU1_SB_DQ<29>")
		)
		(pad "AG19" smd circle
			(at -22.77491 -14.856714 270)
			(size 0.4318 0.4318)
			(layers "F.Cu" "F.Mask" "F.Paste")
			(net "M_C_CPU1_SB_DQ<27>")
		)
		(pad "AG21" smd circle
			(at -21.147278 -14.856714 270)
			(size 0.4318 0.4318)
			(layers "F.Cu" "F.Mask" "F.Paste")
			(net "GND")
		)
		(pad "AG23" smd circle
			(at -19.519392 -14.856714 270)
			(size 0.4318 0.4318)
			(layers "F.Cu" "F.Mask" "F.Paste")
			(net "M_D_CPU1_SB_DQ<22>")
		)
		(pad "AG25" smd circle
			(at -17.89176 -14.856714 270)
			(size 0.4318 0.4318)
			(layers "F.Cu" "F.Mask" "F.Paste")
			(net "M_D_CPU1_SB_DQ<19>")
		)
		(pad "AG27" smd circle
			(at -16.263874 -14.856714 270)
			(size 0.4318 0.4318)
			(layers "F.Cu" "F.Mask" "F.Paste")
			(net "GND")
		)
		(pad "AG29" smd circle
			(at -14.635988 -14.856714 270)
			(size 0.4318 0.4318)
			(layers "F.Cu" "F.Mask" "F.Paste")
			(net "M_C_CPU1_SB_DQ<14>")
		)
		(pad "AG31" smd circle
			(at -13.008356 -14.856714 270)
			(size 0.4318 0.4318)
			(layers "F.Cu" "F.Mask" "F.Paste")
			(net "M_C_CPU1_SB_DQ<11>")
		)
		(pad "AG33" smd circle
			(at -11.380724 -14.856714 270)
			(size 0.4318 0.4318)
			(layers "F.Cu" "F.Mask" "F.Paste")
			(net "GND")
		)
		(pad "AG35" smd circle
			(at -9.752838 -14.856714 270)
			(size 0.4318 0.4318)
			(layers "F.Cu" "F.Mask" "F.Paste")
			(net "M_C_CPU1_SB_DQ<6>")
		)
		(pad "AG37" smd circle
			(at -8.124952 -14.856714 270)
			(size 0.4318 0.4318)
			(layers "F.Cu" "F.Mask" "F.Paste")
			(net "M_C_CPU1_SB_DQ<3>")
		)
		(pad "AG39" smd circle
			(at -6.49732 -14.856714 270)
			(size 0.4318 0.4318)
			(layers "F.Cu" "F.Mask" "F.Paste")
			(net "GND")
		)
		(pad "AG41" smd circle
			(at -4.869434 -14.856714 270)
			(size 0.4318 0.4318)
			(layers "F.Cu" "F.Mask" "F.Paste")
			(net "M_D_CPU1_SB_CS_N<1>")
		)
		(pad "AG43" smd circle
			(at -3.241802 -14.856714 270)
			(size 0.4318 0.4318)
			(layers "F.Cu" "F.Mask" "F.Paste")
			(net "M_D_CPU1_SB_CA<5>")
		)
	)
)
